#ISCELL
  pure_quanta quanta_title_block_c *
  *
#CELL
  pure_quanta pt5161lrs *
  page402_i1
#ISCELL
  standard tap *
  page402_i10
#ISCELL
  standard tap *
  page402_i11
#ISCELL
  standard tap *
  page402_i12
#ISCELL
  standard tap *
  page402_i13
#ISCELL
  standard tap *
  page402_i14
#ISCELL
  standard tap *
  page402_i15
#ISCELL
  standard tap *
  page402_i16
#ISCELL
  standard tap *
  page402_i17
#ISCELL
  standard offpage *
  page402_i18
#ISCELL
  standard offpage *
  page402_i19
#ISCELL
  standard tap *
  page402_i2
#ISCELL
  standard tap *
  page402_i20
#ISCELL
  standard tap *
  page402_i21
#ISCELL
  standard tap *
  page402_i22
#ISCELL
  standard tap *
  page402_i23
#ISCELL
  standard tap *
  page402_i24
#ISCELL
  standard tap *
  page402_i25
#ISCELL
  standard tap *
  page402_i26
#ISCELL
  standard tap *
  page402_i27
#ISCELL
  standard tap *
  page402_i28
#ISCELL
  standard tap *
  page402_i29
#ISCELL
  standard tap *
  page402_i3
#ISCELL
  standard tap *
  page402_i30
#ISCELL
  standard tap *
  page402_i31
#ISCELL
  standard tap *
  page402_i32
#ISCELL
  standard tap *
  page402_i33
#ISCELL
  standard tap *
  page402_i34
#ISCELL
  standard offpage *
  page402_i35
#ISCELL
  standard offpage *
  page402_i36
#ISCELL
  standard tap *
  page402_i37
#CELL
  pure_quanta pt5161lrs *
  page402_i38
#ISCELL
  standard tap *
  page402_i4
#ISCELL
  standard tap *
  page402_i5
#ISCELL
  standard tap *
  page402_i6
#ISCELL
  standard tap *
  page402_i7
#ISCELL
  standard tap *
  page402_i8
#ISCELL
  standard tap *
  page402_i9
